(kicad_pcb
	(version 20260206)
	(generator "pcbnew")
	(generator_version "10.0")
	(general
		(thickness 1.6)
		(legacy_teardrops no)
	)
	(paper "A4")
	(title_block
		(title "03242023_DA0F0TMBIJ0_F0T_Motherboard_J_brd_V01_OCP.brd")
		(comment 1 "Grand Teton / footprints 5498-5503 of 6105")
	)
	(layers
		(0 "F.Cu" signal "TOP")
		(4 "In1.Cu" signal "GND")
		(6 "In2.Cu" signal "IN1")
		(8 "In3.Cu" signal "GND1")
		(10 "In4.Cu" signal "IN2")
		(12 "In5.Cu" signal "GND2")
		(14 "In6.Cu" signal "IN3")
		(16 "In7.Cu" signal "GND3")
		(18 "In8.Cu" signal "VCC")
		(20 "In9.Cu" signal "VCC1")
		(22 "In10.Cu" signal "GND4")
		(24 "In11.Cu" signal "IN4")
		(26 "In12.Cu" signal "GND5")
		(28 "In13.Cu" signal "IN5")
		(30 "In14.Cu" signal "GND6")
		(32 "In15.Cu" signal "IN6")
		(34 "In16.Cu" signal "GND7")
		(2 "B.Cu" signal "BOTTOM")
		(9 "F.Adhes" user "F.Adhesive")
		(11 "B.Adhes" user "B.Adhesive")
		(13 "F.Paste" user "Package Geometry/Pastemask Top")
		(15 "B.Paste" user "Package Geometry/Pastemask Bottom")
		(5 "F.SilkS" user "Ref Des/Silkscreen Top")
		(7 "B.SilkS" user "Ref Des/Silkscreen Bottom")
		(1 "F.Mask" user "Board Geometry/Soldermask Top")
		(3 "B.Mask" user "Board Geometry/Soldermask Bottom")
		(17 "Dwgs.User" user "User.Drawings")
		(19 "Cmts.User" user "User.Comments")
		(21 "Eco1.User" user "User.Eco1")
		(23 "Eco2.User" user "User.Eco2")
		(25 "Edge.Cuts" user "Board Geometry/Outline")
		(27 "Margin" user)
		(31 "F.CrtYd" user "Package Geometry/Place Bound Top")
		(29 "B.CrtYd" user "Package Geometry/Place Bound Bottom")
		(35 "F.Fab" user "Ref Des/Assembly Top")
		(33 "B.Fab" user "Ref Des/Assembly Bottom")
	)
	(footprint ""
		(layer "B.Cu")
		(at 346.44076 -58.38317 45)
		(property "Reference" "C157"
			(at 0 0 45)
			(layer "B.SilkS")
			(hide yes)
			(effects
				(font
					(size 1.27 1.27)
				)
				(justify mirror)
			)
		)
		(property "Value" ""
			(at 0 0 45)
			(layer "B.Fab")
			(effects
				(font
					(size 1.27 1.27)
				)
				(justify mirror)
			)
		)
		(duplicate_pad_numbers_are_jumpers no)
		(fp_line
			(start -0.299941 -0.15015)
			(end -0.299941 0.15015)
			(stroke
				(width 0.1)
				(type default)
			)
			(layer "B.Fab")
		)
		(fp_line
			(start -0.299941 0.15015)
			(end 0.299941 0.15015)
			(stroke
				(width 0.1)
				(type default)
			)
			(layer "B.Fab")
		)
		(fp_line
			(start 0.299941 -0.15015)
			(end -0.299941 -0.15015)
			(stroke
				(width 0.1)
				(type default)
			)
			(layer "B.Fab")
		)
		(fp_line
			(start 0.299941 0.15015)
			(end 0.299941 -0.15015)
			(stroke
				(width 0.1)
				(type default)
			)
			(layer "B.Fab")
		)
		(pad "1" smd rect
			(at 0.266699 0 225)
			(size 0.3048 0.381)
			(layers "B.Cu" "B.Mask" "B.Paste")
			(net "DMI_CPU0_PCH_RX_C_DN<6>")
		)
		(pad "2" smd rect
			(at -0.266699 0 225)
			(size 0.3048 0.381)
			(layers "B.Cu" "B.Mask" "B.Paste")
			(net "DMI_CPU0_PCH_RX_DN<6>")
		)
	)
	(footprint ""
		(layer "B.Cu")
		(at 260.157214 -319.263776 180)
		(property "Reference" "R2731"
			(at 0 0 0)
			(layer "B.SilkS")
			(hide yes)
			(effects
				(font
					(size 1.27 1.27)
				)
				(justify mirror)
			)
		)
		(property "Value" ""
			(at 0 0 0)
			(layer "B.Fab")
			(effects
				(font
					(size 1.27 1.27)
				)
				(justify mirror)
			)
		)
		(duplicate_pad_numbers_are_jumpers no)
		(fp_line
			(start 0.7874 0.4064)
			(end 0.7874 -0.4064)
			(stroke
				(width 0.1524)
				(type default)
			)
			(layer "B.SilkS")
		)
		(fp_line
			(start 0.7874 -0.4064)
			(end -0.7874 -0.4064)
			(stroke
				(width 0.1524)
				(type default)
			)
			(layer "B.SilkS")
		)
		(fp_line
			(start -0.7874 0.4064)
			(end 0.7874 0.4064)
			(stroke
				(width 0.1524)
				(type default)
			)
			(layer "B.SilkS")
		)
		(fp_line
			(start -0.7874 -0.4064)
			(end -0.7874 0.4064)
			(stroke
				(width 0.1524)
				(type default)
			)
			(layer "B.SilkS")
		)
		(fp_line
			(start 0.67945 0.3048)
			(end 0.67945 -0.305054)
			(stroke
				(width 0.1)
				(type default)
			)
			(layer "B.Fab")
		)
		(fp_line
			(start 0.67945 -0.305054)
			(end 0.12065 -0.305054)
			(stroke
				(width 0.1)
				(type default)
			)
			(layer "B.Fab")
		)
		(fp_line
			(start 0.12065 0.3048)
			(end 0.67945 0.3048)
			(stroke
				(width 0.1)
				(type default)
			)
			(layer "B.Fab")
		)
		(fp_line
			(start 0.12065 0.2794)
			(end 0.12065 0.3048)
			(stroke
				(width 0.1)
				(type default)
			)
			(layer "B.Fab")
		)
		(fp_line
			(start 0.12065 -0.2794)
			(end -0.12065 -0.2794)
			(stroke
				(width 0.1)
				(type default)
			)
			(layer "B.Fab")
		)
		(fp_line
			(start 0.12065 -0.305054)
			(end 0.12065 -0.2794)
			(stroke
				(width 0.1)
				(type default)
			)
			(layer "B.Fab")
		)
		(fp_line
			(start -0.120396 0.3048)
			(end -0.120396 0.2794)
			(stroke
				(width 0.1)
				(type default)
			)
			(layer "B.Fab")
		)
		(fp_line
			(start -0.120396 0.2794)
			(end 0.12065 0.2794)
			(stroke
				(width 0.1)
				(type default)
			)
			(layer "B.Fab")
		)
		(fp_line
			(start -0.12065 -0.2794)
			(end -0.12065 -0.3048)
			(stroke
				(width 0.1)
				(type default)
			)
			(layer "B.Fab")
		)
		(fp_line
			(start -0.12065 -0.3048)
			(end -0.67945 -0.3048)
			(stroke
				(width 0.1)
				(type default)
			)
			(layer "B.Fab")
		)
		(fp_line
			(start -0.67945 0.3048)
			(end -0.120396 0.3048)
			(stroke
				(width 0.1)
				(type default)
			)
			(layer "B.Fab")
		)
		(fp_line
			(start -0.67945 -0.3048)
			(end -0.67945 0.3048)
			(stroke
				(width 0.1)
				(type default)
			)
			(layer "B.Fab")
		)
		(pad "1" smd circle
			(at 0.40005 0)
			(size 0 0)
			(layers "B.Cu" "B.Mask" "B.Paste")
			(net "PWRGD_CHD_CPU0_DIMM1")
		)
		(pad "2" smd circle
			(at -0.40005 0)
			(size 0 0)
			(layers "B.Cu" "B.Mask" "B.Paste")
			(net "PWRGD_FAIL_CPU0_CD")
		)
	)
	(footprint ""
		(layer "B.Cu")
		(at 299.129958 -193.67373 90)
		(property "Reference" "R177"
			(at 0 0 90)
			(layer "B.SilkS")
			(hide yes)
			(effects
				(font
					(size 1.27 1.27)
				)
				(justify mirror)
			)
		)
		(property "Value" ""
			(at 0 0 90)
			(layer "B.Fab")
			(effects
				(font
					(size 1.27 1.27)
				)
				(justify mirror)
			)
		)
		(duplicate_pad_numbers_are_jumpers no)
		(fp_line
			(start 0.7874 -0.4064)
			(end -0.7874 -0.4064)
			(stroke
				(width 0.1524)
				(type default)
			)
			(layer "B.SilkS")
		)
		(fp_line
			(start -0.7874 -0.4064)
			(end -0.7874 0.4064)
			(stroke
				(width 0.1524)
				(type default)
			)
			(layer "B.SilkS")
		)
		(fp_line
			(start 0.7874 0.4064)
			(end 0.7874 -0.4064)
			(stroke
				(width 0.1524)
				(type default)
			)
			(layer "B.SilkS")
		)
		(fp_line
			(start -0.7874 0.4064)
			(end 0.7874 0.4064)
			(stroke
				(width 0.1524)
				(type default)
			)
			(layer "B.SilkS")
		)
		(fp_line
			(start 0.67945 -0.305054)
			(end 0.12065 -0.305054)
			(stroke
				(width 0.1)
				(type default)
			)
			(layer "B.Fab")
		)
		(fp_line
			(start 0.12065 -0.305054)
			(end 0.12065 -0.2794)
			(stroke
				(width 0.1)
				(type default)
			)
			(layer "B.Fab")
		)
		(fp_line
			(start -0.12065 -0.3048)
			(end -0.67945 -0.3048)
			(stroke
				(width 0.1)
				(type default)
			)
			(layer "B.Fab")
		)
		(fp_line
			(start -0.67945 -0.3048)
			(end -0.67945 0.3048)
			(stroke
				(width 0.1)
				(type default)
			)
			(layer "B.Fab")
		)
		(fp_line
			(start 0.12065 -0.2794)
			(end -0.12065 -0.2794)
			(stroke
				(width 0.1)
				(type default)
			)
			(layer "B.Fab")
		)
		(fp_line
			(start -0.12065 -0.2794)
			(end -0.12065 -0.3048)
			(stroke
				(width 0.1)
				(type default)
			)
			(layer "B.Fab")
		)
		(fp_line
			(start 0.12065 0.2794)
			(end 0.12065 0.3048)
			(stroke
				(width 0.1)
				(type default)
			)
			(layer "B.Fab")
		)
		(fp_line
			(start -0.120396 0.2794)
			(end 0.12065 0.2794)
			(stroke
				(width 0.1)
				(type default)
			)
			(layer "B.Fab")
		)
		(fp_line
			(start 0.67945 0.3048)
			(end 0.67945 -0.305054)
			(stroke
				(width 0.1)
				(type default)
			)
			(layer "B.Fab")
		)
		(fp_line
			(start 0.12065 0.3048)
			(end 0.67945 0.3048)
			(stroke
				(width 0.1)
				(type default)
			)
			(layer "B.Fab")
		)
		(fp_line
			(start -0.120396 0.3048)
			(end -0.120396 0.2794)
			(stroke
				(width 0.1)
				(type default)
			)
			(layer "B.Fab")
		)
		(fp_line
			(start -0.67945 0.3048)
			(end -0.120396 0.3048)
			(stroke
				(width 0.1)
				(type default)
			)
			(layer "B.Fab")
		)
		(pad "1" smd circle
			(at 0.40005 0 270)
			(size 0 0)
			(layers "B.Cu" "B.Mask" "B.Paste")
			(net "PWRGD_DRAMPWRGD_CPU0_CD_LVC1_R2")
		)
		(pad "2" smd circle
			(at -0.40005 0 270)
			(size 0 0)
			(layers "B.Cu" "B.Mask" "B.Paste")
			(net "PVCCD_HV_CPU0")
		)
	)
	(footprint ""
		(layer "B.Cu")
		(at 248.943368 -105.256584 -90)
		(property "Reference" "R1484"
			(at 0 0 90)
			(layer "B.SilkS")
			(hide yes)
			(effects
				(font
					(size 1.27 1.27)
				)
				(justify mirror)
			)
		)
		(property "Value" ""
			(at 0 0 90)
			(layer "B.Fab")
			(effects
				(font
					(size 1.27 1.27)
				)
				(justify mirror)
			)
		)
		(duplicate_pad_numbers_are_jumpers no)
		(fp_line
			(start -0.7874 0.4064)
			(end 0.7874 0.4064)
			(stroke
				(width 0.1524)
				(type default)
			)
			(layer "B.SilkS")
		)
		(fp_line
			(start 0.7874 0.4064)
			(end 0.7874 -0.4064)
			(stroke
				(width 0.1524)
				(type default)
			)
			(layer "B.SilkS")
		)
		(fp_line
			(start -0.7874 -0.4064)
			(end -0.7874 0.4064)
			(stroke
				(width 0.1524)
				(type default)
			)
			(layer "B.SilkS")
		)
		(fp_line
			(start 0.7874 -0.4064)
			(end -0.7874 -0.4064)
			(stroke
				(width 0.1524)
				(type default)
			)
			(layer "B.SilkS")
		)
		(fp_line
			(start -0.67945 0.3048)
			(end -0.120396 0.3048)
			(stroke
				(width 0.1)
				(type default)
			)
			(layer "B.Fab")
		)
		(fp_line
			(start -0.120396 0.3048)
			(end -0.120396 0.2794)
			(stroke
				(width 0.1)
				(type default)
			)
			(layer "B.Fab")
		)
		(fp_line
			(start 0.12065 0.3048)
			(end 0.67945 0.3048)
			(stroke
				(width 0.1)
				(type default)
			)
			(layer "B.Fab")
		)
		(fp_line
			(start 0.67945 0.3048)
			(end 0.67945 -0.305054)
			(stroke
				(width 0.1)
				(type default)
			)
			(layer "B.Fab")
		)
		(fp_line
			(start -0.120396 0.2794)
			(end 0.12065 0.2794)
			(stroke
				(width 0.1)
				(type default)
			)
			(layer "B.Fab")
		)
		(fp_line
			(start 0.12065 0.2794)
			(end 0.12065 0.3048)
			(stroke
				(width 0.1)
				(type default)
			)
			(layer "B.Fab")
		)
		(fp_line
			(start -0.12065 -0.2794)
			(end -0.12065 -0.3048)
			(stroke
				(width 0.1)
				(type default)
			)
			(layer "B.Fab")
		)
		(fp_line
			(start 0.12065 -0.2794)
			(end -0.12065 -0.2794)
			(stroke
				(width 0.1)
				(type default)
			)
			(layer "B.Fab")
		)
		(fp_line
			(start -0.67945 -0.3048)
			(end -0.67945 0.3048)
			(stroke
				(width 0.1)
				(type default)
			)
			(layer "B.Fab")
		)
		(fp_line
			(start -0.12065 -0.3048)
			(end -0.67945 -0.3048)
			(stroke
				(width 0.1)
				(type default)
			)
			(layer "B.Fab")
		)
		(fp_line
			(start 0.12065 -0.305054)
			(end 0.12065 -0.2794)
			(stroke
				(width 0.1)
				(type default)
			)
			(layer "B.Fab")
		)
		(fp_line
			(start 0.67945 -0.305054)
			(end 0.12065 -0.305054)
			(stroke
				(width 0.1)
				(type default)
			)
			(layer "B.Fab")
		)
		(pad "1" smd circle
			(at 0.40005 0 90)
			(size 0 0)
			(layers "B.Cu" "B.Mask" "B.Paste")
			(net "FM_CK440Q_DEV_25M_EN")
		)
		(pad "2" smd circle
			(at -0.40005 0 90)
			(size 0 0)
			(layers "B.Cu" "B.Mask" "B.Paste")
			(net "GND")
		)
	)
	(footprint ""
		(layer "B.Cu")
		(at 200.031858 -192.95237)
		(property "Reference" "R740"
			(at 0 0 0)
			(layer "B.SilkS")
			(hide yes)
			(effects
				(font
					(size 1.27 1.27)
				)
				(justify mirror)
			)
		)
		(property "Value" ""
			(at 0 0 0)
			(layer "B.Fab")
			(effects
				(font
					(size 1.27 1.27)
				)
				(justify mirror)
			)
		)
		(duplicate_pad_numbers_are_jumpers no)
		(fp_line
			(start -0.7874 -0.4064)
			(end -0.7874 0.4064)
			(stroke
				(width 0.1524)
				(type default)
			)
			(layer "B.SilkS")
		)
		(fp_line
			(start -0.7874 0.4064)
			(end 0.7874 0.4064)
			(stroke
				(width 0.1524)
				(type default)
			)
			(layer "B.SilkS")
		)
		(fp_line
			(start 0.7874 -0.4064)
			(end -0.7874 -0.4064)
			(stroke
				(width 0.1524)
				(type default)
			)
			(layer "B.SilkS")
		)
		(fp_line
			(start 0.7874 0.4064)
			(end 0.7874 -0.4064)
			(stroke
				(width 0.1524)
				(type default)
			)
			(layer "B.SilkS")
		)
		(fp_line
			(start -0.67945 -0.3048)
			(end -0.67945 0.3048)
			(stroke
				(width 0.1)
				(type default)
			)
			(layer "B.Fab")
		)
		(fp_line
			(start -0.67945 0.3048)
			(end -0.120396 0.3048)
			(stroke
				(width 0.1)
				(type default)
			)
			(layer "B.Fab")
		)
		(fp_line
			(start -0.12065 -0.3048)
			(end -0.67945 -0.3048)
			(stroke
				(width 0.1)
				(type default)
			)
			(layer "B.Fab")
		)
		(fp_line
			(start -0.12065 -0.2794)
			(end -0.12065 -0.3048)
			(stroke
				(width 0.1)
				(type default)
			)
			(layer "B.Fab")
		)
		(fp_line
			(start -0.120396 0.2794)
			(end 0.12065 0.2794)
			(stroke
				(width 0.1)
				(type default)
			)
			(layer "B.Fab")
		)
		(fp_line
			(start -0.120396 0.3048)
			(end -0.120396 0.2794)
			(stroke
				(width 0.1)
				(type default)
			)
			(layer "B.Fab")
		)
		(fp_line
			(start 0.12065 -0.305054)
			(end 0.12065 -0.2794)
			(stroke
				(width 0.1)
				(type default)
			)
			(layer "B.Fab")
		)
		(fp_line
			(start 0.12065 -0.2794)
			(end -0.12065 -0.2794)
			(stroke
				(width 0.1)
				(type default)
			)
			(layer "B.Fab")
		)
		(fp_line
			(start 0.12065 0.2794)
			(end 0.12065 0.3048)
			(stroke
				(width 0.1)
				(type default)
			)
			(layer "B.Fab")
		)
		(fp_line
			(start 0.12065 0.3048)
			(end 0.67945 0.3048)
			(stroke
				(width 0.1)
				(type default)
			)
			(layer "B.Fab")
		)
		(fp_line
			(start 0.67945 -0.305054)
			(end 0.12065 -0.305054)
			(stroke
				(width 0.1)
				(type default)
			)
			(layer "B.Fab")
		)
		(fp_line
			(start 0.67945 0.3048)
			(end 0.67945 -0.305054)
			(stroke
				(width 0.1)
				(type default)
			)
			(layer "B.Fab")
		)
		(pad "1" smd circle
			(at 0.40005 0 180)
			(size 0 0)
			(layers "B.Cu" "B.Mask" "B.Paste")
			(net "P3V3_AUX")
		)
		(pad "2" smd circle
			(at -0.40005 0 180)
			(size 0 0)
			(layers "B.Cu" "B.Mask" "B.Paste")
			(net "FM_CPU0_SKTOCC_N")
		)
	)
	(footprint ""
		(layer "B.Cu")
		(at 172.2247 -13.762228 90)
		(property "Reference" "R3858"
			(at 0 0 90)
			(layer "B.SilkS")
			(hide yes)
			(effects
				(font
					(size 1.27 1.27)
				)
				(justify mirror)
			)
		)
		(property "Value" ""
			(at 0 0 90)
			(layer "B.Fab")
			(effects
				(font
					(size 1.27 1.27)
				)
				(justify mirror)
			)
		)
		(duplicate_pad_numbers_are_jumpers no)
		(fp_line
			(start 0.7874 -0.4064)
			(end -0.7874 -0.4064)
			(stroke
				(width 0.1524)
				(type default)
			)
			(layer "B.SilkS")
		)
		(fp_line
			(start -0.7874 -0.4064)
			(end -0.7874 0.4064)
			(stroke
				(width 0.1524)
				(type default)
			)
			(layer "B.SilkS")
		)
		(fp_line
			(start 0.7874 0.4064)
			(end 0.7874 -0.4064)
			(stroke
				(width 0.1524)
				(type default)
			)
			(layer "B.SilkS")
		)
		(fp_line
			(start -0.7874 0.4064)
			(end 0.7874 0.4064)
			(stroke
				(width 0.1524)
				(type default)
			)
			(layer "B.SilkS")
		)
		(fp_line
			(start 0.67945 -0.305054)
			(end 0.12065 -0.305054)
			(stroke
				(width 0.1)
				(type default)
			)
			(layer "B.Fab")
		)
		(fp_line
			(start 0.12065 -0.305054)
			(end 0.12065 -0.2794)
			(stroke
				(width 0.1)
				(type default)
			)
			(layer "B.Fab")
		)
		(fp_line
			(start -0.12065 -0.3048)
			(end -0.67945 -0.3048)
			(stroke
				(width 0.1)
				(type default)
			)
			(layer "B.Fab")
		)
		(fp_line
			(start -0.67945 -0.3048)
			(end -0.67945 0.3048)
			(stroke
				(width 0.1)
				(type default)
			)
			(layer "B.Fab")
		)
		(fp_line
			(start 0.12065 -0.2794)
			(end -0.12065 -0.2794)
			(stroke
				(width 0.1)
				(type default)
			)
			(layer "B.Fab")
		)
		(fp_line
			(start -0.12065 -0.2794)
			(end -0.12065 -0.3048)
			(stroke
				(width 0.1)
				(type default)
			)
			(layer "B.Fab")
		)
		(fp_line
			(start 0.12065 0.2794)
			(end 0.12065 0.3048)
			(stroke
				(width 0.1)
				(type default)
			)
			(layer "B.Fab")
		)
		(fp_line
			(start -0.120396 0.2794)
			(end 0.12065 0.2794)
			(stroke
				(width 0.1)
				(type default)
			)
			(layer "B.Fab")
		)
		(fp_line
			(start 0.67945 0.3048)
			(end 0.67945 -0.305054)
			(stroke
				(width 0.1)
				(type default)
			)
			(layer "B.Fab")
		)
		(fp_line
			(start 0.12065 0.3048)
			(end 0.67945 0.3048)
			(stroke
				(width 0.1)
				(type default)
			)
			(layer "B.Fab")
		)
		(fp_line
			(start -0.120396 0.3048)
			(end -0.120396 0.2794)
			(stroke
				(width 0.1)
				(type default)
			)
			(layer "B.Fab")
		)
		(fp_line
			(start -0.67945 0.3048)
			(end -0.120396 0.3048)
			(stroke
				(width 0.1)
				(type default)
			)
			(layer "B.Fab")
		)
		(pad "1" smd circle
			(at 0.40005 0 270)
			(size 0 0)
			(layers "B.Cu" "B.Mask" "B.Paste")
			(net "SMB_OCP_V3_2_3V3AUX_SDA")
		)
		(pad "2" smd circle
			(at -0.40005 0 270)
			(size 0 0)
			(layers "B.Cu" "B.Mask" "B.Paste")
			(net "SMB_OCP_V3_2_3V3AUX_SDA_R0")
		)
	)
)
